(kicad_pcb
	(version 20260206)
	(generator "pcbnew")
	(generator_version "10.0")
	(general
		(thickness 1.6)
		(legacy_teardrops no)
	)
	(paper "A4")
	(title_block
		(title "01162023_DA0F0TEBIF0_F0T_Expander_BD_F_brd_V02_OCP.brd")
		(comment 1 "Grand Teton / footprints 6151-6156 of 9728")
	)
	(layers
		(0 "F.Cu" signal "TOP")
		(4 "In1.Cu" signal "GND")
		(6 "In2.Cu" signal "VCC")
		(8 "In3.Cu" signal "VCC1")
		(10 "In4.Cu" signal "GND1")
		(12 "In5.Cu" signal "IN1")
		(14 "In6.Cu" signal "GND2")
		(16 "In7.Cu" signal "IN2")
		(18 "In8.Cu" signal "GND3")
		(20 "In9.Cu" signal "IN3")
		(22 "In10.Cu" signal "GND4")
		(24 "In11.Cu" signal "IN4")
		(26 "In12.Cu" signal "GND5")
		(28 "In13.Cu" signal "IN5")
		(30 "In14.Cu" signal "GND6")
		(32 "In15.Cu" signal "IN6")
		(34 "In16.Cu" signal "GND7")
		(2 "B.Cu" signal "BOTTOM")
		(9 "F.Adhes" user "F.Adhesive")
		(11 "B.Adhes" user "B.Adhesive")
		(13 "F.Paste" user "Package Geometry/Pastemask Top")
		(15 "B.Paste" user "Package Geometry/Pastemask Bottom")
		(5 "F.SilkS" user "Ref Des/Silkscreen Top")
		(7 "B.SilkS" user "Ref Des/Silkscreen Bottom")
		(1 "F.Mask" user "Board Geometry/Soldermask Top")
		(3 "B.Mask" user "Board Geometry/Soldermask Bottom")
		(17 "Dwgs.User" user "User.Drawings")
		(19 "Cmts.User" user "User.Comments")
		(21 "Eco1.User" user "User.Eco1")
		(23 "Eco2.User" user "User.Eco2")
		(25 "Edge.Cuts" user "Board Geometry/Outline")
		(27 "Margin" user)
		(31 "F.CrtYd" user "Package Geometry/Place Bound Top")
		(29 "B.CrtYd" user "Package Geometry/Place Bound Bottom")
		(35 "F.Fab" user "Ref Des/Assembly Top")
		(33 "B.Fab" user "Ref Des/Assembly Bottom")
	)
	(footprint ""
		(layer "F.Cu")
		(at 81.357724 -27.006296 -90)
		(property "Reference" "PR6925"
			(at 0 0 270)
			(layer "F.SilkS")
			(hide yes)
			(effects
				(font
					(size 1.27 1.27)
				)
			)
		)
		(property "Value" ""
			(at 0 0 270)
			(layer "F.Fab")
			(effects
				(font
					(size 1.27 1.27)
				)
			)
		)
		(duplicate_pad_numbers_are_jumpers no)
		(fp_line
			(start -0.7874 0.4064)
			(end -0.7874 -0.4064)
			(stroke
				(width 0.1524)
				(type default)
			)
			(layer "F.SilkS")
		)
		(fp_line
			(start 0.7874 0.4064)
			(end -0.7874 0.4064)
			(stroke
				(width 0.1524)
				(type default)
			)
			(layer "F.SilkS")
		)
		(fp_line
			(start -0.7874 -0.4064)
			(end 0.7874 -0.4064)
			(stroke
				(width 0.1524)
				(type default)
			)
			(layer "F.SilkS")
		)
		(fp_line
			(start 0.7874 -0.4064)
			(end 0.7874 0.4064)
			(stroke
				(width 0.1524)
				(type default)
			)
			(layer "F.SilkS")
		)
		(fp_line
			(start -0.67945 0.3048)
			(end -0.67945 -0.305054)
			(stroke
				(width 0.1)
				(type default)
			)
			(layer "F.Fab")
		)
		(fp_line
			(start -0.12065 0.3048)
			(end -0.67945 0.3048)
			(stroke
				(width 0.1)
				(type default)
			)
			(layer "F.Fab")
		)
		(fp_line
			(start 0.120396 0.3048)
			(end 0.120396 0.2794)
			(stroke
				(width 0.1)
				(type default)
			)
			(layer "F.Fab")
		)
		(fp_line
			(start 0.67945 0.3048)
			(end 0.120396 0.3048)
			(stroke
				(width 0.1)
				(type default)
			)
			(layer "F.Fab")
		)
		(fp_line
			(start -0.12065 0.2794)
			(end -0.12065 0.3048)
			(stroke
				(width 0.1)
				(type default)
			)
			(layer "F.Fab")
		)
		(fp_line
			(start 0.120396 0.2794)
			(end -0.12065 0.2794)
			(stroke
				(width 0.1)
				(type default)
			)
			(layer "F.Fab")
		)
		(fp_line
			(start -0.12065 -0.2794)
			(end 0.12065 -0.2794)
			(stroke
				(width 0.1)
				(type default)
			)
			(layer "F.Fab")
		)
		(fp_line
			(start 0.12065 -0.2794)
			(end 0.12065 -0.3048)
			(stroke
				(width 0.1)
				(type default)
			)
			(layer "F.Fab")
		)
		(fp_line
			(start 0.12065 -0.3048)
			(end 0.67945 -0.3048)
			(stroke
				(width 0.1)
				(type default)
			)
			(layer "F.Fab")
		)
		(fp_line
			(start 0.67945 -0.3048)
			(end 0.67945 0.3048)
			(stroke
				(width 0.1)
				(type default)
			)
			(layer "F.Fab")
		)
		(fp_line
			(start -0.67945 -0.305054)
			(end -0.12065 -0.305054)
			(stroke
				(width 0.1)
				(type default)
			)
			(layer "F.Fab")
		)
		(fp_line
			(start -0.12065 -0.305054)
			(end -0.12065 -0.2794)
			(stroke
				(width 0.1)
				(type default)
			)
			(layer "F.Fab")
		)
		(pad "1" smd circle
			(at -0.40005 0 270)
			(size 0 0)
			(layers "F.Cu" "F.Mask" "F.Paste")
			(net "P3V3_SSD3_CO_MODE")
		)
		(pad "2" smd circle
			(at 0.40005 0 270)
			(size 0 0)
			(layers "F.Cu" "F.Mask" "F.Paste")
			(net "GND")
		)
	)
	(footprint ""
		(layer "F.Cu")
		(at 228.79304 -93.057726)
		(property "Reference" "R1021"
			(at 0 0 0)
			(layer "F.SilkS")
			(hide yes)
			(effects
				(font
					(size 1.27 1.27)
				)
			)
		)
		(property "Value" ""
			(at 0 0 0)
			(layer "F.Fab")
			(effects
				(font
					(size 1.27 1.27)
				)
			)
		)
		(duplicate_pad_numbers_are_jumpers no)
		(fp_line
			(start -0.7874 -0.4064)
			(end 0.7874 -0.4064)
			(stroke
				(width 0.1524)
				(type default)
			)
			(layer "F.SilkS")
		)
		(fp_line
			(start -0.7874 0.4064)
			(end -0.7874 -0.4064)
			(stroke
				(width 0.1524)
				(type default)
			)
			(layer "F.SilkS")
		)
		(fp_line
			(start 0.7874 -0.4064)
			(end 0.7874 0.4064)
			(stroke
				(width 0.1524)
				(type default)
			)
			(layer "F.SilkS")
		)
		(fp_line
			(start 0.7874 0.4064)
			(end -0.7874 0.4064)
			(stroke
				(width 0.1524)
				(type default)
			)
			(layer "F.SilkS")
		)
		(fp_line
			(start -0.67945 -0.305054)
			(end -0.12065 -0.305054)
			(stroke
				(width 0.1)
				(type default)
			)
			(layer "F.Fab")
		)
		(fp_line
			(start -0.67945 0.3048)
			(end -0.67945 -0.305054)
			(stroke
				(width 0.1)
				(type default)
			)
			(layer "F.Fab")
		)
		(fp_line
			(start -0.12065 -0.305054)
			(end -0.12065 -0.2794)
			(stroke
				(width 0.1)
				(type default)
			)
			(layer "F.Fab")
		)
		(fp_line
			(start -0.12065 -0.2794)
			(end 0.12065 -0.2794)
			(stroke
				(width 0.1)
				(type default)
			)
			(layer "F.Fab")
		)
		(fp_line
			(start -0.12065 0.2794)
			(end -0.12065 0.3048)
			(stroke
				(width 0.1)
				(type default)
			)
			(layer "F.Fab")
		)
		(fp_line
			(start -0.12065 0.3048)
			(end -0.67945 0.3048)
			(stroke
				(width 0.1)
				(type default)
			)
			(layer "F.Fab")
		)
		(fp_line
			(start 0.120396 0.2794)
			(end -0.12065 0.2794)
			(stroke
				(width 0.1)
				(type default)
			)
			(layer "F.Fab")
		)
		(fp_line
			(start 0.120396 0.3048)
			(end 0.120396 0.2794)
			(stroke
				(width 0.1)
				(type default)
			)
			(layer "F.Fab")
		)
		(fp_line
			(start 0.12065 -0.3048)
			(end 0.67945 -0.3048)
			(stroke
				(width 0.1)
				(type default)
			)
			(layer "F.Fab")
		)
		(fp_line
			(start 0.12065 -0.2794)
			(end 0.12065 -0.3048)
			(stroke
				(width 0.1)
				(type default)
			)
			(layer "F.Fab")
		)
		(fp_line
			(start 0.67945 -0.3048)
			(end 0.67945 0.3048)
			(stroke
				(width 0.1)
				(type default)
			)
			(layer "F.Fab")
		)
		(fp_line
			(start 0.67945 0.3048)
			(end 0.120396 0.3048)
			(stroke
				(width 0.1)
				(type default)
			)
			(layer "F.Fab")
		)
		(pad "1" smd circle
			(at -0.40005 0)
			(size 0 0)
			(layers "F.Cu" "F.Mask" "F.Paste")
			(net "GND")
		)
		(pad "2" smd circle
			(at 0.40005 0)
			(size 0 0)
			(layers "F.Cu" "F.Mask" "F.Paste")
			(net "PEX_USB_HUB_PSELF")
		)
	)
	(footprint ""
		(layer "F.Cu")
		(at 328.126344 -25.432004 -90)
		(property "Reference" "C976"
			(at 0 0 270)
			(layer "F.SilkS")
			(hide yes)
			(effects
				(font
					(size 1.27 1.27)
				)
			)
		)
		(property "Value" ""
			(at 0 0 270)
			(layer "F.Fab")
			(effects
				(font
					(size 1.27 1.27)
				)
			)
		)
		(duplicate_pad_numbers_are_jumpers no)
		(fp_line
			(start -0.7874 0.4064)
			(end -0.7874 -0.4064)
			(stroke
				(width 0.1524)
				(type default)
			)
			(layer "F.SilkS")
		)
		(fp_line
			(start 0.7874 0.4064)
			(end -0.7874 0.4064)
			(stroke
				(width 0.1524)
				(type default)
			)
			(layer "F.SilkS")
		)
		(fp_line
			(start -0.7874 -0.4064)
			(end 0.7874 -0.4064)
			(stroke
				(width 0.1524)
				(type default)
			)
			(layer "F.SilkS")
		)
		(fp_line
			(start 0.7874 -0.4064)
			(end 0.7874 0.4064)
			(stroke
				(width 0.1524)
				(type default)
			)
			(layer "F.SilkS")
		)
		(fp_line
			(start -0.67945 0.3048)
			(end -0.67945 -0.305054)
			(stroke
				(width 0.1)
				(type default)
			)
			(layer "F.Fab")
		)
		(fp_line
			(start -0.12065 0.3048)
			(end -0.67945 0.3048)
			(stroke
				(width 0.1)
				(type default)
			)
			(layer "F.Fab")
		)
		(fp_line
			(start 0.120396 0.3048)
			(end 0.120396 0.2794)
			(stroke
				(width 0.1)
				(type default)
			)
			(layer "F.Fab")
		)
		(fp_line
			(start 0.67945 0.3048)
			(end 0.120396 0.3048)
			(stroke
				(width 0.1)
				(type default)
			)
			(layer "F.Fab")
		)
		(fp_line
			(start -0.12065 0.2794)
			(end -0.12065 0.3048)
			(stroke
				(width 0.1)
				(type default)
			)
			(layer "F.Fab")
		)
		(fp_line
			(start 0.120396 0.2794)
			(end -0.12065 0.2794)
			(stroke
				(width 0.1)
				(type default)
			)
			(layer "F.Fab")
		)
		(fp_line
			(start -0.12065 -0.2794)
			(end 0.12065 -0.2794)
			(stroke
				(width 0.1)
				(type default)
			)
			(layer "F.Fab")
		)
		(fp_line
			(start 0.12065 -0.2794)
			(end 0.12065 -0.3048)
			(stroke
				(width 0.1)
				(type default)
			)
			(layer "F.Fab")
		)
		(fp_line
			(start 0.12065 -0.3048)
			(end 0.67945 -0.3048)
			(stroke
				(width 0.1)
				(type default)
			)
			(layer "F.Fab")
		)
		(fp_line
			(start 0.67945 -0.3048)
			(end 0.67945 0.3048)
			(stroke
				(width 0.1)
				(type default)
			)
			(layer "F.Fab")
		)
		(fp_line
			(start -0.67945 -0.305054)
			(end -0.12065 -0.305054)
			(stroke
				(width 0.1)
				(type default)
			)
			(layer "F.Fab")
		)
		(fp_line
			(start -0.12065 -0.305054)
			(end -0.12065 -0.2794)
			(stroke
				(width 0.1)
				(type default)
			)
			(layer "F.Fab")
		)
		(pad "1" smd circle
			(at -0.40005 0 270)
			(size 0 0)
			(layers "F.Cu" "F.Mask" "F.Paste")
			(net "GND")
		)
		(pad "2" smd circle
			(at 0.40005 0 270)
			(size 0 0)
			(layers "F.Cu" "F.Mask" "F.Paste")
			(net "P3V3_SSD11")
		)
	)
	(footprint ""
		(layer "F.Cu")
		(at 95.271336 -121.291858)
		(property "Reference" "PU48"
			(at -0.863854 2.828798 0)
			(unlocked yes)
			(layer "F.SilkS")
			(effects
				(font
					(size 0.7874 0.5842)
					(thickness 0.1524)
				)
				(justify left)
			)
		)
		(property "Value" ""
			(at 0 0 0)
			(layer "F.Fab")
			(effects
				(font
					(size 1.27 1.27)
				)
			)
		)
		(duplicate_pad_numbers_are_jumpers no)
		(fp_line
			(start -1.943608 -1.549908)
			(end 1.943608 -1.549908)
			(stroke
				(width 0.1524)
				(type default)
			)
			(layer "F.SilkS")
		)
		(fp_line
			(start -1.943608 1.549908)
			(end -1.943608 -1.549908)
			(stroke
				(width 0.1524)
				(type default)
			)
			(layer "F.SilkS")
		)
		(fp_line
			(start 1.943608 -1.549908)
			(end 1.943608 1.549908)
			(stroke
				(width 0.1524)
				(type default)
			)
			(layer "F.SilkS")
		)
		(fp_line
			(start 1.943608 1.549908)
			(end -1.943608 1.549908)
			(stroke
				(width 0.1524)
				(type default)
			)
			(layer "F.SilkS")
		)
		(fp_poly
			(pts
				(xy -2.019808 -1.549908) (xy -1.257808 -1.549908) (xy -1.257808 -1.880108) (xy -2.019808 -1.880108)
			)
			(stroke
				(width 0)
				(type default)
			)
			(fill yes)
			(layer "F.SilkS")
		)
		(fp_line
			(start -1.549908 -1.549908)
			(end 1.549908 -1.549908)
			(stroke
				(width 0.1)
				(type default)
			)
			(layer "F.Fab")
		)
		(fp_line
			(start -1.549908 1.549908)
			(end -1.549908 -1.549908)
			(stroke
				(width 0.1)
				(type default)
			)
			(layer "F.Fab")
		)
		(fp_line
			(start 1.549908 -1.549908)
			(end 1.549908 1.549908)
			(stroke
				(width 0.1)
				(type default)
			)
			(layer "F.Fab")
		)
		(fp_line
			(start 1.549908 1.549908)
			(end -1.549908 1.549908)
			(stroke
				(width 0.1)
				(type default)
			)
			(layer "F.Fab")
		)
		(fp_poly
			(pts
				(xy -2.019808 -1.549908) (xy -1.257808 -1.549908) (xy -1.257808 -1.880108) (xy -2.019808 -1.880108)
			)
			(stroke
				(width 0)
				(type default)
			)
			(fill yes)
			(layer "F.Fab")
		)
		(pad "1" smd rect
			(at -1.500124 -1.249934 270)
			(size 0.2794 0.6096)
			(layers "F.Cu" "F.Mask" "F.Paste")
			(net "P3V3_NIC1")
		)
		(pad "2" smd rect
			(at -1.500124 -0.750062 270)
			(size 0.2794 0.6096)
			(layers "F.Cu" "F.Mask" "F.Paste")
			(net "P3V3_NIC1")
		)
		(pad "3" smd rect
			(at -1.500124 -0.249936 270)
			(size 0.2794 0.6096)
			(layers "F.Cu" "F.Mask" "F.Paste")
			(net "P3V3_NIC1")
		)
		(pad "4" smd rect
			(at -1.500124 0.249936 270)
			(size 0.2794 0.6096)
			(layers "F.Cu" "F.Mask" "F.Paste")
			(net "P3V3_NIC1")
		)
		(pad "5" smd rect
			(at -1.500124 0.750062 270)
			(size 0.2794 0.6096)
			(layers "F.Cu" "F.Mask" "F.Paste")
			(net "P3V3_NIC1")
		)
		(pad "6" smd rect
			(at -1.500124 1.249934 270)
			(size 0.2794 0.6096)
			(layers "F.Cu" "F.Mask" "F.Paste")
			(net "GND")
		)
		(pad "7" smd rect
			(at 1.500124 1.249934 270)
			(size 0.2794 0.6096)
			(layers "F.Cu" "F.Mask" "F.Paste")
			(net "P3V3_NIC1_SS")
		)
		(pad "8" smd rect
			(at 1.500124 0.750062 270)
			(size 0.2794 0.6096)
			(layers "F.Cu" "F.Mask" "F.Paste")
			(net "PWRGD_P3V3_NIC1")
		)
		(pad "9" smd rect
			(at 1.500124 0.249936 270)
			(size 0.2794 0.6096)
			(layers "F.Cu" "F.Mask" "F.Paste")
			(net "P3V3_NIC1_OCP")
		)
		(pad "10" smd rect
			(at 1.500124 -0.249936 270)
			(size 0.2794 0.6096)
			(layers "F.Cu" "F.Mask" "F.Paste")
			(net "P5V_AUX")
		)
		(pad "11" smd rect
			(at 1.500124 -0.750062 270)
			(size 0.2794 0.6096)
			(layers "F.Cu" "F.Mask" "F.Paste")
			(net "HP_NIC1_EN")
		)
		(pad "12" smd rect
			(at 1.500124 -1.249934 270)
			(size 0.2794 0.6096)
			(layers "F.Cu" "F.Mask" "F.Paste")
			(net "P3V3_AUX")
		)
		(pad "13" smd rect
			(at 0 0)
			(size 1.9812 2.7178)
			(layers "F.Cu" "F.Mask" "F.Paste")
			(net "P3V3_AUX")
		)
		(zone
			(layer "F.Cu")
			(hatch none 0.5)
			(connect_pads
				(clearance 0)
			)
			(min_thickness 0.25)
			(keepout
				(tracks not_allowed)
				(vias allowed)
				(pads allowed)
				(copperpour not_allowed)
				(footprints allowed)
			)
			(placement
				(enabled no)
				(sheetname "")
			)
			(fill
				(thermal_gap 0.5)
				(thermal_bridge_width 0.5)
				(island_removal_mode 0)
			)
			(polygon
				(pts
					(xy 96.414336 -122.841258) (xy 96.414336 -122.714258) (xy 96.414336 -119.742458) (xy 96.414336 -119.74195)
					(xy 94.128336 -119.74195) (xy 94.128336 -119.742458) (xy 94.128336 -119.869458) (xy 94.128336 -121.291858)
					(xy 94.229936 -121.291858) (xy 94.229936 -119.869458) (xy 96.312736 -119.869458) (xy 96.312736 -122.714258)
					(xy 94.229936 -122.714258) (xy 94.229936 -121.317258) (xy 94.128336 -121.317258) (xy 94.128336 -122.714258)
					(xy 94.128336 -122.841258) (xy 94.128336 -122.841766) (xy 96.414336 -122.841766)
				)
			)
		)
	)
	(footprint ""
		(layer "F.Cu")
		(at 258.242562 -212.765386 180)
		(property "Reference" "R2520"
			(at 0 0 180)
			(layer "F.SilkS")
			(hide yes)
			(effects
				(font
					(size 1.27 1.27)
				)
			)
		)
		(property "Value" ""
			(at 0 0 180)
			(layer "F.Fab")
			(effects
				(font
					(size 1.27 1.27)
				)
			)
		)
		(duplicate_pad_numbers_are_jumpers no)
		(fp_line
			(start 0.7874 0.4064)
			(end -0.7874 0.4064)
			(stroke
				(width 0.1524)
				(type default)
			)
			(layer "F.SilkS")
		)
		(fp_line
			(start 0.7874 -0.4064)
			(end 0.7874 0.4064)
			(stroke
				(width 0.1524)
				(type default)
			)
			(layer "F.SilkS")
		)
		(fp_line
			(start -0.7874 0.4064)
			(end -0.7874 -0.4064)
			(stroke
				(width 0.1524)
				(type default)
			)
			(layer "F.SilkS")
		)
		(fp_line
			(start -0.7874 -0.4064)
			(end 0.7874 -0.4064)
			(stroke
				(width 0.1524)
				(type default)
			)
			(layer "F.SilkS")
		)
		(fp_line
			(start 0.67945 0.3048)
			(end 0.120396 0.3048)
			(stroke
				(width 0.1)
				(type default)
			)
			(layer "F.Fab")
		)
		(fp_line
			(start 0.67945 -0.3048)
			(end 0.67945 0.3048)
			(stroke
				(width 0.1)
				(type default)
			)
			(layer "F.Fab")
		)
		(fp_line
			(start 0.12065 -0.2794)
			(end 0.12065 -0.3048)
			(stroke
				(width 0.1)
				(type default)
			)
			(layer "F.Fab")
		)
		(fp_line
			(start 0.12065 -0.3048)
			(end 0.67945 -0.3048)
			(stroke
				(width 0.1)
				(type default)
			)
			(layer "F.Fab")
		)
		(fp_line
			(start 0.120396 0.3048)
			(end 0.120396 0.2794)
			(stroke
				(width 0.1)
				(type default)
			)
			(layer "F.Fab")
		)
		(fp_line
			(start 0.120396 0.2794)
			(end -0.12065 0.2794)
			(stroke
				(width 0.1)
				(type default)
			)
			(layer "F.Fab")
		)
		(fp_line
			(start -0.12065 0.3048)
			(end -0.67945 0.3048)
			(stroke
				(width 0.1)
				(type default)
			)
			(layer "F.Fab")
		)
		(fp_line
			(start -0.12065 0.2794)
			(end -0.12065 0.3048)
			(stroke
				(width 0.1)
				(type default)
			)
			(layer "F.Fab")
		)
		(fp_line
			(start -0.12065 -0.2794)
			(end 0.12065 -0.2794)
			(stroke
				(width 0.1)
				(type default)
			)
			(layer "F.Fab")
		)
		(fp_line
			(start -0.12065 -0.305054)
			(end -0.12065 -0.2794)
			(stroke
				(width 0.1)
				(type default)
			)
			(layer "F.Fab")
		)
		(fp_line
			(start -0.67945 0.3048)
			(end -0.67945 -0.305054)
			(stroke
				(width 0.1)
				(type default)
			)
			(layer "F.Fab")
		)
		(fp_line
			(start -0.67945 -0.305054)
			(end -0.12065 -0.305054)
			(stroke
				(width 0.1)
				(type default)
			)
			(layer "F.Fab")
		)
		(pad "1" smd circle
			(at -0.40005 0 180)
			(size 0 0)
			(layers "F.Cu" "F.Mask" "F.Paste")
			(net "P3V3_AUX")
		)
		(pad "2" smd circle
			(at 0.40005 0 180)
			(size 0 0)
			(layers "F.Cu" "F.Mask" "F.Paste")
			(net "PWR_EN_P1V2_AUX_R")
		)
	)
	(footprint ""
		(layer "F.Cu")
		(at 165.269672 -350.098614 90)
		(property "Reference" "C398"
			(at 0 0 90)
			(layer "F.SilkS")
			(hide yes)
			(effects
				(font
					(size 1.27 1.27)
				)
			)
		)
		(property "Value" ""
			(at 0 0 90)
			(layer "F.Fab")
			(effects
				(font
					(size 1.27 1.27)
				)
			)
		)
		(duplicate_pad_numbers_are_jumpers no)
		(fp_line
			(start 0.299974 -0.150114)
			(end 0.299974 0.150114)
			(stroke
				(width 0.1)
				(type default)
			)
			(layer "F.Fab")
		)
		(fp_line
			(start -0.299974 -0.150114)
			(end 0.299974 -0.150114)
			(stroke
				(width 0.1)
				(type default)
			)
			(layer "F.Fab")
		)
		(fp_line
			(start 0.299974 0.150114)
			(end -0.299974 0.150114)
			(stroke
				(width 0.1)
				(type default)
			)
			(layer "F.Fab")
		)
		(fp_line
			(start -0.299974 0.150114)
			(end -0.299974 -0.150114)
			(stroke
				(width 0.1)
				(type default)
			)
			(layer "F.Fab")
		)
		(pad "1" smd rect
			(at -0.2667 0 90)
			(size 0.3048 0.381)
			(layers "F.Cu" "F.Mask" "F.Paste")
			(net "P5E_PEX1_STN7_TX_DP<114>")
		)
		(pad "2" smd rect
			(at 0.2667 0 90)
			(size 0.3048 0.381)
			(layers "F.Cu" "F.Mask" "F.Paste")
			(net "P5E_PEX1_STN7_TX_C_DP<114>")
		)
	)
)
